`timescale 1 ns/1 ps

module p3_3vstby (g );
// generated by Concept HDL Direct Version 05.20-p009 02-Dec-98
// on Mon Oct 09 11:18:27 2000
// from symbols/P3_3VSTBY/sch_1


  inout  g;
  // global signal glbl.p3_3vstby;



  `ifdef VAN

  wire  page1_g;
  wire  p3_3vstby;
  wire  page1_p3_3vstby;

  assign page1_g = g;
  assign p3_3vstby = glbl.p3_3vstby;
  assign page1_p3_3vstby = p3_3vstby;

  `endif


  `ifdef VAN

  assign g  = glbl.p3_3vstby;

  `else
  alias_bit alias_inst1 (g, glbl.p3_3vstby);

  `endif

// begin instances 

endmodule // p3_3vstby(sch_1) 
